(kicad_pcb
	(version 20260206)
	(generator "pcbnew")
	(generator_version "10.0")
	(general
		(thickness 1.6)
		(legacy_teardrops no)
	)
	(paper "A4")
	(title_block
		(title "01162023_DA0F0TEBIF0_F0T_Expander_BD_F_brd_V02_OCP.brd")
		(comment 1 "Grand Teton / footprint 1670 of 9728 (J24), pads 110-179 of 179")
	)
	(layers
		(0 "F.Cu" signal "TOP")
		(4 "In1.Cu" signal "GND")
		(6 "In2.Cu" signal "VCC")
		(8 "In3.Cu" signal "VCC1")
		(10 "In4.Cu" signal "GND1")
		(12 "In5.Cu" signal "IN1")
		(14 "In6.Cu" signal "GND2")
		(16 "In7.Cu" signal "IN2")
		(18 "In8.Cu" signal "GND3")
		(20 "In9.Cu" signal "IN3")
		(22 "In10.Cu" signal "GND4")
		(24 "In11.Cu" signal "IN4")
		(26 "In12.Cu" signal "GND5")
		(28 "In13.Cu" signal "IN5")
		(30 "In14.Cu" signal "GND6")
		(32 "In15.Cu" signal "IN6")
		(34 "In16.Cu" signal "GND7")
		(2 "B.Cu" signal "BOTTOM")
		(9 "F.Adhes" user "F.Adhesive")
		(11 "B.Adhes" user "B.Adhesive")
		(13 "F.Paste" user "Package Geometry/Pastemask Top")
		(15 "B.Paste" user "Package Geometry/Pastemask Bottom")
		(5 "F.SilkS" user "Ref Des/Silkscreen Top")
		(7 "B.SilkS" user "Ref Des/Silkscreen Bottom")
		(1 "F.Mask" user "Board Geometry/Soldermask Top")
		(3 "B.Mask" user "Board Geometry/Soldermask Bottom")
		(17 "Dwgs.User" user "User.Drawings")
		(19 "Cmts.User" user "User.Comments")
		(21 "Eco1.User" user "User.Eco1")
		(23 "Eco2.User" user "User.Eco2")
		(25 "Edge.Cuts" user "Board Geometry/Outline")
		(27 "Margin" user)
		(31 "F.CrtYd" user "Package Geometry/Place Bound Top")
		(29 "B.CrtYd" user "Package Geometry/Place Bound Bottom")
		(35 "F.Fab" user "Ref Des/Assembly Top")
		(33 "B.Fab" user "Ref Des/Assembly Bottom")
	)
	(footprint ""
		(layer "F.Cu")
		(at 279.519888 -127.700024)
		(property "Reference" "J24"
			(at -5.198618 34.837624 90)
			(unlocked yes)
			(layer "F.SilkS")
			(effects
				(font
					(size 0.7874 0.5842)
					(thickness 0.1524)
				)
				(justify left)
			)
		)
		(property "Value" ""
			(at 0 0 0)
			(layer "F.Fab")
			(effects
				(font
					(size 1.27 1.27)
				)
			)
		)
		(duplicate_pad_numbers_are_jumpers no)
		(pad "B38" smd rect
			(at -1.27762 7.14502 270)
			(size 0.3556 1.2192)
			(layers "F.Cu" "F.Mask" "F.Paste")
			(net "GND")
		)
		(pad "B39" smd rect
			(at -1.27762 7.744968 270)
			(size 0.3556 1.2192)
			(layers "F.Cu" "F.Mask" "F.Paste")
			(net "P5E_PEX2_STN1_TX_C_DN<24>")
		)
		(pad "B40" smd rect
			(at -1.27762 8.344916 270)
			(size 0.3556 1.2192)
			(layers "F.Cu" "F.Mask" "F.Paste")
			(net "P5E_PEX2_STN1_TX_C_DP<24>")
		)
		(pad "B41" smd rect
			(at -1.27762 8.945118 270)
			(size 0.3556 1.2192)
			(layers "F.Cu" "F.Mask" "F.Paste")
			(net "GND")
		)
		(pad "B42" smd rect
			(at -1.27762 9.545066 270)
			(size 0.3556 1.2192)
			(layers "F.Cu" "F.Mask" "F.Paste")
			(net "PRSNTB0_NIC4_N")
		)
		(pad "B43" smd rect
			(at -1.27762 14.454886 270)
			(size 0.3556 1.2192)
			(layers "F.Cu" "F.Mask" "F.Paste")
			(net "GND")
		)
		(pad "B44" smd rect
			(at -1.27762 15.055088 270)
			(size 0.3556 1.2192)
			(layers "F.Cu" "F.Mask" "F.Paste")
			(net "P5E_PEX2_STN1_TX_C_DP<23>")
		)
		(pad "B45" smd rect
			(at -1.27762 15.655036 270)
			(size 0.3556 1.2192)
			(layers "F.Cu" "F.Mask" "F.Paste")
			(net "P5E_PEX2_STN1_TX_C_DN<23>")
		)
		(pad "B46" smd rect
			(at -1.27762 16.254984 270)
			(size 0.3556 1.2192)
			(layers "F.Cu" "F.Mask" "F.Paste")
			(net "GND")
		)
		(pad "B47" smd rect
			(at -1.27762 16.854932 270)
			(size 0.3556 1.2192)
			(layers "F.Cu" "F.Mask" "F.Paste")
			(net "P5E_PEX2_STN1_TX_C_DN<22>")
		)
		(pad "B48" smd rect
			(at -1.27762 17.45488 270)
			(size 0.3556 1.2192)
			(layers "F.Cu" "F.Mask" "F.Paste")
			(net "P5E_PEX2_STN1_TX_C_DP<22>")
		)
		(pad "B49" smd rect
			(at -1.27762 18.055082 270)
			(size 0.3556 1.2192)
			(layers "F.Cu" "F.Mask" "F.Paste")
			(net "GND")
		)
		(pad "B50" smd rect
			(at -1.27762 18.65503 270)
			(size 0.3556 1.2192)
			(layers "F.Cu" "F.Mask" "F.Paste")
			(net "P5E_PEX2_STN1_TX_C_DP<21>")
		)
		(pad "B51" smd rect
			(at -1.27762 19.254978 270)
			(size 0.3556 1.2192)
			(layers "F.Cu" "F.Mask" "F.Paste")
			(net "P5E_PEX2_STN1_TX_C_DN<21>")
		)
		(pad "B52" smd rect
			(at -1.27762 19.854926 270)
			(size 0.3556 1.2192)
			(layers "F.Cu" "F.Mask" "F.Paste")
			(net "GND")
		)
		(pad "B53" smd rect
			(at -1.27762 20.455128 270)
			(size 0.3556 1.2192)
			(layers "F.Cu" "F.Mask" "F.Paste")
			(net "P5E_PEX2_STN1_TX_C_DN<20>")
		)
		(pad "B54" smd rect
			(at -1.27762 21.055076 270)
			(size 0.3556 1.2192)
			(layers "F.Cu" "F.Mask" "F.Paste")
			(net "P5E_PEX2_STN1_TX_C_DP<20>")
		)
		(pad "B55" smd rect
			(at -1.27762 21.655024 270)
			(size 0.3556 1.2192)
			(layers "F.Cu" "F.Mask" "F.Paste")
			(net "GND")
		)
		(pad "B56" smd rect
			(at -1.27762 22.254972 270)
			(size 0.3556 1.2192)
			(layers "F.Cu" "F.Mask" "F.Paste")
			(net "P5E_PEX2_STN1_TX_C_DP<19>")
		)
		(pad "B57" smd rect
			(at -1.27762 22.85492 270)
			(size 0.3556 1.2192)
			(layers "F.Cu" "F.Mask" "F.Paste")
			(net "P5E_PEX2_STN1_TX_C_DN<19>")
		)
		(pad "B58" smd rect
			(at -1.27762 23.455122 270)
			(size 0.3556 1.2192)
			(layers "F.Cu" "F.Mask" "F.Paste")
			(net "GND")
		)
		(pad "B59" smd rect
			(at -1.27762 24.05507 270)
			(size 0.3556 1.2192)
			(layers "F.Cu" "F.Mask" "F.Paste")
			(net "P5E_PEX2_STN1_TX_C_DN<18>")
		)
		(pad "B60" smd rect
			(at -1.27762 24.655018 270)
			(size 0.3556 1.2192)
			(layers "F.Cu" "F.Mask" "F.Paste")
			(net "P5E_PEX2_STN1_TX_C_DP<18>")
		)
		(pad "B61" smd rect
			(at -1.27762 25.254966 270)
			(size 0.3556 1.2192)
			(layers "F.Cu" "F.Mask" "F.Paste")
			(net "GND")
		)
		(pad "B62" smd rect
			(at -1.27762 25.854914 270)
			(size 0.3556 1.2192)
			(layers "F.Cu" "F.Mask" "F.Paste")
			(net "P5E_PEX2_STN1_TX_C_DP<17>")
		)
		(pad "B63" smd rect
			(at -1.27762 26.455116 270)
			(size 0.3556 1.2192)
			(layers "F.Cu" "F.Mask" "F.Paste")
			(net "P5E_PEX2_STN1_TX_C_DN<17>")
		)
		(pad "B64" smd rect
			(at -1.27762 27.055064 270)
			(size 0.3556 1.2192)
			(layers "F.Cu" "F.Mask" "F.Paste")
			(net "GND")
		)
		(pad "B65" smd rect
			(at -1.27762 27.655012 270)
			(size 0.3556 1.2192)
			(layers "F.Cu" "F.Mask" "F.Paste")
			(net "P5E_PEX2_STN1_TX_C_DN<16>")
		)
		(pad "B66" smd rect
			(at -1.27762 28.25496 270)
			(size 0.3556 1.2192)
			(layers "F.Cu" "F.Mask" "F.Paste")
			(net "P5E_PEX2_STN1_TX_C_DP<16>")
		)
		(pad "B67" smd rect
			(at -1.27762 28.854908 270)
			(size 0.3556 1.2192)
			(layers "F.Cu" "F.Mask" "F.Paste")
			(net "GND")
		)
		(pad "B68" smd rect
			(at -1.27762 29.45511 270)
			(size 0.3556 1.2192)
			(layers "F.Cu" "F.Mask" "F.Paste")
			(net "Net_2633")
		)
		(pad "B69" smd rect
			(at -1.27762 30.055058 270)
			(size 0.3556 1.2192)
			(layers "F.Cu" "F.Mask" "F.Paste")
			(net "Net_2634")
		)
		(pad "B70" smd rect
			(at -1.27762 30.655006 270)
			(size 0.3556 1.2192)
			(layers "F.Cu" "F.Mask" "F.Paste")
			(net "PRSNTB3_NIC4_N")
		)
		(pad "G1" thru_hole oval
			(at 1.022604 -34.034984 270)
			(size 1.6256 3.4798)
			(drill oval 1.1176 2.4638)
			(layers "*.Cu" "*.Mask")
			(remove_unused_layers no)
			(net "GND")
			(clearance 0.127)
			(thermal_gap 0.127)
		)
		(pad "G2" thru_hole oval
			(at 1.022604 -20.625054 270)
			(size 1.6256 3.4798)
			(drill oval 1.1176 2.4638)
			(layers "*.Cu" "*.Mask")
			(remove_unused_layers no)
			(net "GND")
			(clearance 0.127)
			(thermal_gap 0.127)
		)
		(pad "G3" thru_hole oval
			(at 1.022604 -0.255016 270)
			(size 1.6256 3.4798)
			(drill oval 1.1176 2.4638)
			(layers "*.Cu" "*.Mask")
			(remove_unused_layers no)
			(net "GND")
			(clearance 0.127)
			(thermal_gap 0.127)
		)
		(pad "G4" thru_hole oval
			(at 1.022604 12.005056 270)
			(size 1.6256 3.4798)
			(drill oval 1.1176 2.4638)
			(layers "*.Cu" "*.Mask")
			(remove_unused_layers no)
			(net "GND")
			(clearance 0.127)
			(thermal_gap 0.127)
		)
		(pad "G5" thru_hole oval
			(at 1.022604 34.034984 270)
			(size 1.5748 3.4798)
			(drill oval 1.1176 2.4638)
			(layers "*.Cu" "*.Mask")
			(remove_unused_layers no)
			(net "GND")
			(clearance 0.1524)
			(thermal_gap 0.1524)
		)
		(pad "G6" thru_hole circle
			(at -3.16738 -20.625054)
			(size 1.6256 1.6256)
			(drill 1.1176)
			(layers "*.Cu" "*.Mask")
			(remove_unused_layers no)
			(net "GND")
			(clearance 0)
		)
		(pad "G7" thru_hole circle
			(at -3.16738 12.005056)
			(size 1.6256 1.6256)
			(drill 1.1176)
			(layers "*.Cu" "*.Mask")
			(remove_unused_layers no)
			(net "GND")
			(clearance 0)
		)
		(pad "G8" thru_hole circle
			(at 4.20243 -20.625054)
			(size 1.6256 1.6256)
			(drill 1.1176)
			(layers "*.Cu" "*.Mask")
			(remove_unused_layers no)
			(net "GND")
			(clearance 0)
		)
		(pad "G9" thru_hole circle
			(at 4.20243 12.005056)
			(size 1.6256 1.6256)
			(drill 1.1176)
			(layers "*.Cu" "*.Mask")
			(remove_unused_layers no)
			(net "GND")
			(clearance 0)
		)
		(pad "OA1" smd rect
			(at 3.322574 -30.660086 270)
			(size 0.3556 1.2192)
			(layers "F.Cu" "F.Mask" "F.Paste")
			(net "RST_NIC4_PERST2_R_N")
		)
		(pad "OA2" smd rect
			(at 3.322574 -30.059884 270)
			(size 0.3556 1.2192)
			(layers "F.Cu" "F.Mask" "F.Paste")
			(net "RST_NIC4_PERST3_R_N")
		)
		(pad "OA3" smd rect
			(at 3.322574 -29.459936 270)
			(size 0.3556 1.2192)
			(layers "F.Cu" "F.Mask" "F.Paste")
			(net "Net_2637")
		)
		(pad "OA4" smd rect
			(at 3.322574 -28.859988 270)
			(size 0.3556 1.2192)
			(layers "F.Cu" "F.Mask" "F.Paste")
			(net "NIC4_RBT_ARB_IN")
		)
		(pad "OA5" smd rect
			(at 3.322574 -28.26004 270)
			(size 0.3556 1.2192)
			(layers "F.Cu" "F.Mask" "F.Paste")
			(net "NIC4_RBT_ARB_OUT")
		)
		(pad "OA6" smd rect
			(at 3.322574 -27.660092 270)
			(size 0.3556 1.2192)
			(layers "F.Cu" "F.Mask" "F.Paste")
			(net "NIC4_SLOT_ID1")
		)
		(pad "OA7" smd rect
			(at 3.322574 -27.05989 270)
			(size 0.3556 1.2192)
			(layers "F.Cu" "F.Mask" "F.Paste")
			(net "NCSI_NIC4_TX_EN")
		)
		(pad "OA8" smd rect
			(at 3.322574 -26.459942 270)
			(size 0.3556 1.2192)
			(layers "F.Cu" "F.Mask" "F.Paste")
			(net "NCSI_NIC4_TXD1")
		)
		(pad "OA9" smd rect
			(at 3.322574 -25.859994 270)
			(size 0.3556 1.2192)
			(layers "F.Cu" "F.Mask" "F.Paste")
			(net "NCSI_NIC4_TXD0")
		)
		(pad "OA10" smd rect
			(at 3.322574 -25.260046 270)
			(size 0.3556 1.2192)
			(layers "F.Cu" "F.Mask" "F.Paste")
			(net "GND")
		)
		(pad "OA11" smd rect
			(at 3.322574 -24.660098 270)
			(size 0.3556 1.2192)
			(layers "F.Cu" "F.Mask" "F.Paste")
			(net "Net_2629")
		)
		(pad "OA12" smd rect
			(at 3.322574 -24.059896 270)
			(size 0.3556 1.2192)
			(layers "F.Cu" "F.Mask" "F.Paste")
			(net "Net_2632")
		)
		(pad "OA13" smd rect
			(at 3.322574 -23.459948 270)
			(size 0.3556 1.2192)
			(layers "F.Cu" "F.Mask" "F.Paste")
			(net "GND")
		)
		(pad "OA14" smd rect
			(at 3.322574 -22.86 270)
			(size 0.3556 1.2192)
			(layers "F.Cu" "F.Mask" "F.Paste")
			(net "CLK_50M_NIC4_RBT_REF")
		)
		(pad "OB1" smd rect
			(at -1.27762 -30.660086 270)
			(size 0.3556 1.2192)
			(layers "F.Cu" "F.Mask" "F.Paste")
			(net "PWRGD_NIC4_PWR_GOOD")
		)
		(pad "OB2" smd rect
			(at -1.27762 -30.059884 270)
			(size 0.3556 1.2192)
			(layers "F.Cu" "F.Mask" "F.Paste")
			(net "NIC4_MAIN_PWR_EN_R")
		)
		(pad "OB3" smd rect
			(at -1.27762 -29.459936 270)
			(size 0.3556 1.2192)
			(layers "F.Cu" "F.Mask" "F.Paste")
			(net "NIC4_LD_N")
		)
		(pad "OB4" smd rect
			(at -1.27762 -28.859988 270)
			(size 0.3556 1.2192)
			(layers "F.Cu" "F.Mask" "F.Paste")
			(net "NIC4_DATA_IN")
		)
		(pad "OB5" smd rect
			(at -1.27762 -28.26004 270)
			(size 0.3556 1.2192)
			(layers "F.Cu" "F.Mask" "F.Paste")
			(net "NIC4_DATA_OUT")
		)
		(pad "OB6" smd rect
			(at -1.27762 -27.660092 270)
			(size 0.3556 1.2192)
			(layers "F.Cu" "F.Mask" "F.Paste")
			(net "NIC4_CLK")
		)
		(pad "OB7" smd rect
			(at -1.27762 -27.05989 270)
			(size 0.3556 1.2192)
			(layers "F.Cu" "F.Mask" "F.Paste")
			(net "NIC4_SLOT_ID0")
		)
		(pad "OB8" smd rect
			(at -1.27762 -26.459942 270)
			(size 0.3556 1.2192)
			(layers "F.Cu" "F.Mask" "F.Paste")
			(net "NCSI_NIC4_RXD1")
		)
		(pad "OB9" smd rect
			(at -1.27762 -25.859994 270)
			(size 0.3556 1.2192)
			(layers "F.Cu" "F.Mask" "F.Paste")
			(net "NCSI_NIC4_RXD0")
		)
		(pad "OB10" smd rect
			(at -1.27762 -25.260046 270)
			(size 0.3556 1.2192)
			(layers "F.Cu" "F.Mask" "F.Paste")
			(net "GND")
		)
		(pad "OB11" smd rect
			(at -1.27762 -24.660098 270)
			(size 0.3556 1.2192)
			(layers "F.Cu" "F.Mask" "F.Paste")
			(net "Net_2628")
		)
		(pad "OB12" smd rect
			(at -1.27762 -24.059896 270)
			(size 0.3556 1.2192)
			(layers "F.Cu" "F.Mask" "F.Paste")
			(net "Net_2631")
		)
		(pad "OB13" smd rect
			(at -1.27762 -23.459948 270)
			(size 0.3556 1.2192)
			(layers "F.Cu" "F.Mask" "F.Paste")
			(net "GND")
		)
		(pad "OB14" smd rect
			(at -1.27762 -22.86 270)
			(size 0.3556 1.2192)
			(layers "F.Cu" "F.Mask" "F.Paste")
			(net "NCSI_NIC4_CRS_DV")
		)
	)
)
